# TIMECARD (Time Appliance Project (Time Card)) — schematic netlist excerpt (pin names and nets, part order shuffled) for the footprints in the layout excerpt that follows; sources: Cadence DE-HDL packaged netlist, KiCad conversion of R4006-B0001-02_R01.brd

C161  CAPACITOR  0.1UF 10V 10%  pkg SMC_0402R_H022  page 14 : \1\ = XP1R0V_FPGA_VCCINT ; \2\ = SG
R332  RESISTOR  33OHM 1%  pkg SMC_0402R_H016  page 17 : \1\ = LM75B_I2C_SDA ; \2\ = R_LM75B_1_I2C_SDA

(kicad_pcb
	(version 20260206)
	(generator "pcbnew")
	(generator_version "10.0")
	(general
		(thickness 1.6)
		(legacy_teardrops no)
	)
	(paper "A4")
	(title_block
		(title "timecard-production-celestica-r4006 — R4006-B0001-02_R01.brd")
		(comment 1 "Time Appliance Project (Time Card) / footprints 950-951 of 1113")
	)
	(layers
		(0 "F.Cu" signal "TOP")
		(4 "In1.Cu" signal "L02_GND1")
		(6 "In2.Cu" signal "L03_SIG1")
		(8 "In3.Cu" signal "L04_GND2")
		(10 "In4.Cu" signal "L05_VCC1")
		(12 "In5.Cu" signal "L06_VCC2")
		(14 "In6.Cu" signal "L07_GND3")
		(16 "In7.Cu" signal "L08_SIG2")
		(18 "In8.Cu" signal "L09_GND4")
		(2 "B.Cu" signal "BOTTOM")
		(9 "F.Adhes" user "F.Adhesive")
		(11 "B.Adhes" user "B.Adhesive")
		(13 "F.Paste" user "Package Geometry/Pastemask Top")
		(15 "B.Paste" user "Package Geometry/Pastemask Bottom")
		(5 "F.SilkS" user "Ref Des/Silkscreen Top")
		(7 "B.SilkS" user "Ref Des/Silkscreen Bottom")
		(1 "F.Mask" user "Board Geometry/Soldermask Top")
		(3 "B.Mask" user "Board Geometry/Soldermask Bottom")
		(17 "Dwgs.User" user "User.Drawings")
		(19 "Cmts.User" user "User.Comments")
		(21 "Eco1.User" user "User.Eco1")
		(23 "Eco2.User" user "User.Eco2")
		(25 "Edge.Cuts" user "Board Geometry/Outline")
		(27 "Margin" user)
		(31 "F.CrtYd" user "Package Geometry/Place Bound Top")
		(29 "B.CrtYd" user "Package Geometry/Place Bound Bottom")
		(35 "F.Fab" user "Ref Des/Assembly Top")
		(33 "B.Fab" user "Ref Des/Assembly Bottom")
	)
	(footprint ""
		(layer "B.Cu")
		(at 16.764 -77.089 90)
		(property "Reference" "R332"
			(at -1.143 3.13563 270)
			(unlocked yes)
			(layer "B.SilkS")
			(effects
				(font
					(size 0.7874 0.5842)
					(thickness 0.1524)
				)
				(justify mirror)
			)
		)
		(property "Value" "VAL*"
			(at -0.02032 2.13233 90)
			(unlocked yes)
			(layer "B.Fab")
			(hide yes)
			(effects
				(font
					(size 0.7874 0.5842)
					(thickness 0.1524)
				)
				(justify mirror)
			)
		)
		(property "Tolerance" "TOL*"
			(at -0.044704 3.05435 90)
			(unlocked yes)
			(layer "Cmts.User")
			(hide yes)
			(effects
				(font
					(size 0.7874 0.5842)
					(thickness 0.1524)
				)
				(justify mirror)
			)
		)
		(property "User Part Number" "PARTNUM*"
			(at -0.02032 4.024884 90)
			(unlocked yes)
			(layer "Cmts.User")
			(hide yes)
			(effects
				(font
					(size 0.7874 0.5842)
					(thickness 0.1524)
				)
				(justify mirror)
			)
		)
		(property "Device Type" "RESISTOR-G155-133R0-01,33OHM,1%"
			(at -0.008382 1.210564 90)
			(unlocked yes)
			(layer "B.Fab")
			(hide yes)
			(effects
				(font
					(size 0.7874 0.5842)
					(thickness 0.1524)
				)
				(justify mirror)
			)
		)
		(duplicate_pad_numbers_are_jumpers no)
		(fp_line
			(start 1.143 -0.5588)
			(end 1.143 0.5588)
			(stroke
				(width 0.1)
				(type default)
			)
			(layer "B.SilkS")
		)
		(fp_line
			(start -1.143 -0.5588)
			(end 1.143 -0.5588)
			(stroke
				(width 0.1)
				(type default)
			)
			(layer "B.SilkS")
		)
		(fp_line
			(start 1.143 0.5588)
			(end -1.143 0.5588)
			(stroke
				(width 0.1)
				(type default)
			)
			(layer "B.SilkS")
		)
		(fp_line
			(start -1.143 0.5588)
			(end -1.143 -0.5588)
			(stroke
				(width 0.1)
				(type default)
			)
			(layer "B.SilkS")
		)
		(fp_rect
			(start 1.143 -0.5588)
			(end -1.143 0.5588)
			(stroke
				(width 0)
				(type default)
			)
			(fill no)
			(layer "B.CrtYd")
		)
		(fp_line
			(start 0.508 -0.3048)
			(end 0.508 0.3048)
			(stroke
				(width 0.1)
				(type default)
			)
			(layer "B.Fab")
		)
		(fp_line
			(start -0.508 -0.3048)
			(end 0.508 -0.3048)
			(stroke
				(width 0.1)
				(type default)
			)
			(layer "B.Fab")
		)
		(fp_line
			(start 0.508 0.3048)
			(end -0.508 0.3048)
			(stroke
				(width 0.1)
				(type default)
			)
			(layer "B.Fab")
		)
		(fp_line
			(start -0.508 0.3048)
			(end -0.508 -0.3048)
			(stroke
				(width 0.1)
				(type default)
			)
			(layer "B.Fab")
		)
		(pad "1" smd rect
			(at 0.5334 0 270)
			(size 0.7112 0.6096)
			(layers "B.Cu" "B.Mask" "B.Paste")
			(net "LM75B_I2C_SDA")
		)
		(pad "2" smd rect
			(at -0.5334 0 270)
			(size 0.7112 0.6096)
			(layers "B.Cu" "B.Mask" "B.Paste")
			(net "R_LM75B_1_I2C_SDA")
		)
		(zone
			(layer "B.Cu")
			(hatch none 0.5)
			(connect_pads
				(clearance 0)
			)
			(min_thickness 0.25)
			(keepout
				(tracks allowed)
				(vias not_allowed)
				(pads allowed)
				(copperpour not_allowed)
				(footprints allowed)
			)
			(placement
				(enabled no)
				(sheetname "")
			)
			(fill
				(thermal_gap 0.5)
				(thermal_bridge_width 0.5)
				(island_removal_mode 0)
			)
			(polygon
				(pts
					(xy 16.4592 -77.1652) (xy 16.4592 -77.0128) (xy 17.0688 -77.0128) (xy 17.0688 -77.1652)
				)
			)
		)
	)
	(footprint ""
		(layer "B.Cu")
		(at 112.84712 -40.323262 -90)
		(property "Reference" "C161"
			(at 1.397762 42.01795 270)
			(unlocked yes)
			(layer "B.SilkS")
			(effects
				(font
					(size 0.635 0.4064)
					(thickness 0.1524)
				)
				(justify mirror)
			)
		)
		(property "Value" "VAL*"
			(at 0 3.718306 270)
			(unlocked yes)
			(layer "B.Fab")
			(hide yes)
			(effects
				(font
					(size 0.7874 0.5842)
					(thickness 0.127)
				)
				(justify mirror)
			)
		)
		(property "Device Type" "CAPACITOR-G105-0B104-CK,0.1UF,A"
			(at 0 1.432306 270)
			(unlocked yes)
			(layer "B.Fab")
			(hide yes)
			(effects
				(font
					(size 0.7874 0.5842)
					(thickness 0.127)
				)
				(justify mirror)
			)
		)
		(property "User Part Number" "PARTNUM*"
			(at 0 2.575306 270)
			(unlocked yes)
			(layer "Cmts.User")
			(hide yes)
			(effects
				(font
					(size 0.7874 0.5842)
					(thickness 0.127)
				)
				(justify mirror)
			)
		)
		(property "Tolerance" "TOL*"
			(at 0 4.861306 270)
			(unlocked yes)
			(layer "Cmts.User")
			(hide yes)
			(effects
				(font
					(size 0.7874 0.5842)
					(thickness 0.127)
				)
				(justify mirror)
			)
		)
		(duplicate_pad_numbers_are_jumpers no)
		(fp_line
			(start -0.970026 0.4699)
			(end 0.970026 0.4699)
			(stroke
				(width 0.1)
				(type default)
			)
			(layer "B.SilkS")
		)
		(fp_line
			(start 0.970026 0.4699)
			(end 0.970026 -0.4699)
			(stroke
				(width 0.1)
				(type default)
			)
			(layer "B.SilkS")
		)
		(fp_line
			(start -0.970026 -0.4699)
			(end -0.970026 0.4699)
			(stroke
				(width 0.1)
				(type default)
			)
			(layer "B.SilkS")
		)
		(fp_line
			(start 0.970026 -0.4699)
			(end -0.970026 -0.4699)
			(stroke
				(width 0.1)
				(type default)
			)
			(layer "B.SilkS")
		)
		(fp_poly
			(pts
				(xy 0.970026 0.4699) (xy -0.970026 0.4699) (xy -0.970026 -0.4699) (xy 0.970026 -0.4699)
			)
			(stroke
				(width 0)
				(type default)
			)
			(fill no)
			(layer "B.CrtYd")
		)
		(fp_line
			(start -0.508 0.3048)
			(end 0.508 0.3048)
			(stroke
				(width 0.1)
				(type default)
			)
			(layer "B.Fab")
		)
		(fp_line
			(start 0.508 0.3048)
			(end 0.508 -0.3048)
			(stroke
				(width 0.1)
				(type default)
			)
			(layer "B.Fab")
		)
		(fp_line
			(start -0.508 -0.3048)
			(end -0.508 0.3048)
			(stroke
				(width 0.1)
				(type default)
			)
			(layer "B.Fab")
		)
		(fp_line
			(start 0.508 -0.3048)
			(end -0.508 -0.3048)
			(stroke
				(width 0.1)
				(type default)
			)
			(layer "B.Fab")
		)
		(pad "1" smd circle
			(at 0.500126 0 90)
			(size 0.635 0.635)
			(layers "B.Cu" "B.Mask" "B.Paste")
			(net "XP1R0V_FPGA_VCCINT")
		)
		(pad "2" smd circle
			(at -0.500126 0 90)
			(size 0.635 0.635)
			(layers "B.Cu" "B.Mask" "B.Paste")
			(net "SG")
		)
	)
)
